# BASEBOARD_FAB2 (Tioga Pass) — schematic netlist excerpt (pin names and nets, part order shuffled) for the footprints in the layout excerpt that follows; sources: Cadence DE-HDL packaged netlist, KiCad conversion of Wiwynn_Tioga_Pass_MB.brd

C1M6  CAP  0.22UF 16V 10% X7R  pkg 0402  page 106 : A = P3E_CPU0_PE3_OCP_TXP<15> ; B = P3E_OCP_CPU0_PE3_C_TXP<15>
C2T3  CAP_A  0.1UF 16V 10% X7R  pkg 0402V  page 157 : A = P3V3_STBY ; B = GND
C8P1  CAP  100UF 4V 20% X5R  pkg 0805  page 228 : A = PVDDQ_KLM ; B = GND

(kicad_pcb
	(version 20260206)
	(generator "pcbnew")
	(generator_version "10.0")
	(general
		(thickness 1.6)
		(legacy_teardrops no)
	)
	(paper "A4")
	(title_block
		(title "Wiwynn_Tioga_Pass_MB.brd")
		(comment 1 "Tioga Pass / footprints 2667-2669 of 4770")
	)
	(layers
		(0 "F.Cu" signal "TOP")
		(4 "In1.Cu" signal "L2GND")
		(6 "In2.Cu" signal "L3")
		(8 "In3.Cu" signal "L4GND")
		(10 "In4.Cu" signal "L5")
		(12 "In5.Cu" signal "L6GND")
		(14 "In6.Cu" signal "L7VCC")
		(16 "In7.Cu" signal "L8VCC")
		(18 "In8.Cu" signal "L9GND")
		(20 "In9.Cu" signal "L10")
		(22 "In10.Cu" signal "L11GND")
		(24 "In11.Cu" signal "L12")
		(26 "In12.Cu" signal "L13GND")
		(2 "B.Cu" signal "BOTTOM")
		(9 "F.Adhes" user "F.Adhesive")
		(11 "B.Adhes" user "B.Adhesive")
		(13 "F.Paste" user "Package Geometry/Pastemask Top")
		(15 "B.Paste" user "Package Geometry/Pastemask Bottom")
		(5 "F.SilkS" user "Ref Des/Silkscreen Top")
		(7 "B.SilkS" user "Ref Des/Silkscreen Bottom")
		(1 "F.Mask" user "Board Geometry/Soldermask Top")
		(3 "B.Mask" user "Board Geometry/Soldermask Bottom")
		(17 "Dwgs.User" user "User.Drawings")
		(19 "Cmts.User" user "User.Comments")
		(21 "Eco1.User" user "User.Eco1")
		(23 "Eco2.User" user "User.Eco2")
		(25 "Edge.Cuts" user "Board Geometry/Outline")
		(27 "Margin" user)
		(31 "F.CrtYd" user "Package Geometry/Place Bound Top")
		(29 "B.CrtYd" user "Package Geometry/Place Bound Bottom")
		(35 "F.Fab" user "Ref Des/Assembly Top")
		(33 "B.Fab" user "Ref Des/Assembly Bottom")
	)
	(footprint ""
		(layer "B.Cu")
		(at 466.344 -116.49202)
		(property "Reference" "C1M6"
			(at 0 0 0)
			(layer "B.SilkS")
			(hide yes)
			(effects
				(font
					(size 1.27 1.27)
				)
				(justify mirror)
			)
		)
		(property "Value" ""
			(at 0 0 0)
			(layer "B.Fab")
			(effects
				(font
					(size 1.27 1.27)
				)
				(justify mirror)
			)
		)
		(duplicate_pad_numbers_are_jumpers no)
		(fp_rect
			(start -0.3048 0.9906)
			(end 0.3048 -0.1016)
			(stroke
				(width 0)
				(type default)
			)
			(fill no)
			(layer "B.CrtYd")
		)
		(fp_line
			(start -0.3048 -0.1016)
			(end 0.3048 -0.1016)
			(stroke
				(width 0.1)
				(type default)
			)
			(layer "B.Fab")
		)
		(fp_line
			(start -0.3048 0.9906)
			(end -0.3048 -0.1016)
			(stroke
				(width 0.1)
				(type default)
			)
			(layer "B.Fab")
		)
		(fp_line
			(start 0.3048 -0.1016)
			(end 0.3048 0.9906)
			(stroke
				(width 0.1)
				(type default)
			)
			(layer "B.Fab")
		)
		(fp_line
			(start 0.3048 0.9906)
			(end -0.3048 0.9906)
			(stroke
				(width 0.1)
				(type default)
			)
			(layer "B.Fab")
		)
		(pad "1" smd rect
			(at 0 0 180)
			(size 0.508 0.508)
			(layers "B.Cu" "B.Mask" "B.Paste")
			(net "P3E_CPU0_PE3_OCP_TXP<15>")
		)
		(pad "2" smd rect
			(at 0 0.889 180)
			(size 0.508 0.508)
			(layers "B.Cu" "B.Mask" "B.Paste")
			(net "P3E_OCP_CPU0_PE3_C_TXP<15>")
		)
		(zone
			(layer "B.Cu")
			(hatch none 0.5)
			(connect_pads
				(clearance 0)
			)
			(min_thickness 0.25)
			(keepout
				(tracks allowed)
				(vias not_allowed)
				(pads allowed)
				(copperpour not_allowed)
				(footprints allowed)
			)
			(placement
				(enabled no)
				(sheetname "")
			)
			(fill
				(thermal_gap 0.5)
				(thermal_bridge_width 0.5)
				(island_removal_mode 0)
			)
			(polygon
				(pts
					(xy 466.09 -115.85702) (xy 466.598 -115.85702) (xy 466.598 -116.23802) (xy 466.09 -116.23802)
				)
			)
		)
		(zone
			(layer "B.Cu")
			(hatch none 0.5)
			(connect_pads
				(clearance 0)
			)
			(min_thickness 0.25)
			(keepout
				(tracks not_allowed)
				(vias allowed)
				(pads allowed)
				(copperpour not_allowed)
				(footprints allowed)
			)
			(placement
				(enabled no)
				(sheetname "")
			)
			(fill
				(thermal_gap 0.5)
				(thermal_bridge_width 0.5)
				(island_removal_mode 0)
			)
			(polygon
				(pts
					(xy 466.09 -115.85702) (xy 466.598 -115.85702) (xy 466.598 -116.23802) (xy 466.09 -116.23802)
				)
			)
		)
	)
	(footprint ""
		(layer "B.Cu")
		(at 102.551992 -85.075014)
		(property "Reference" "C8P1"
			(at 0 0 0)
			(layer "B.SilkS")
			(hide yes)
			(effects
				(font
					(size 1.27 1.27)
				)
				(justify mirror)
			)
		)
		(property "Value" ""
			(at 0 0 0)
			(layer "B.Fab")
			(effects
				(font
					(size 1.27 1.27)
				)
				(justify mirror)
			)
		)
		(duplicate_pad_numbers_are_jumpers no)
		(fp_poly
			(pts
				(xy 0.7239 -0.2159) (xy -0.7239 -0.2159) (xy -0.7239 1.9939) (xy 0.7239 1.9939)
			)
			(stroke
				(width 0)
				(type default)
			)
			(fill no)
			(layer "B.CrtYd")
		)
		(fp_line
			(start -0.7239 -0.2159)
			(end 0.7239 -0.2159)
			(stroke
				(width 0.1)
				(type default)
			)
			(layer "B.Fab")
		)
		(fp_line
			(start -0.7239 1.9939)
			(end -0.7239 -0.2159)
			(stroke
				(width 0.1)
				(type default)
			)
			(layer "B.Fab")
		)
		(fp_line
			(start 0.7239 -0.2159)
			(end 0.7239 1.9939)
			(stroke
				(width 0.1)
				(type default)
			)
			(layer "B.Fab")
		)
		(fp_line
			(start 0.7239 1.9939)
			(end -0.7239 1.9939)
			(stroke
				(width 0.1)
				(type default)
			)
			(layer "B.Fab")
		)
		(pad "1" smd rect
			(at 0 0 180)
			(size 1.27 1.016)
			(layers "B.Cu" "B.Mask" "B.Paste")
			(net "PVDDQ_KLM")
		)
		(pad "2" smd rect
			(at 0 1.778 180)
			(size 1.27 1.016)
			(layers "B.Cu" "B.Mask" "B.Paste")
			(net "GND")
		)
		(zone
			(layer "B.Cu")
			(hatch none 0.5)
			(connect_pads
				(clearance 0)
			)
			(min_thickness 0.25)
			(keepout
				(tracks not_allowed)
				(vias allowed)
				(pads allowed)
				(copperpour not_allowed)
				(footprints allowed)
			)
			(placement
				(enabled no)
				(sheetname "")
			)
			(fill
				(thermal_gap 0.5)
				(thermal_bridge_width 0.5)
				(island_removal_mode 0)
			)
			(polygon
				(pts
					(xy 103.186992 -84.567014) (xy 101.916992 -84.567014) (xy 101.916992 -83.805014) (xy 103.186992 -83.805014)
				)
			)
		)
	)
	(footprint ""
		(layer "B.Cu")
		(at 406.4762 -13.8303 180)
		(property "Reference" "C2T3"
			(at 0 0 0)
			(layer "B.SilkS")
			(hide yes)
			(effects
				(font
					(size 1.27 1.27)
				)
				(justify mirror)
			)
		)
		(property "Value" ""
			(at 0 0 0)
			(layer "B.Fab")
			(effects
				(font
					(size 1.27 1.27)
				)
				(justify mirror)
			)
		)
		(duplicate_pad_numbers_are_jumpers no)
		(fp_poly
			(pts
				(xy -0.3048 -0.1016) (xy -0.3048 0.9906) (xy 0.3048 0.9906) (xy 0.3048 -0.1016)
			)
			(stroke
				(width 0)
				(type default)
			)
			(fill no)
			(layer "B.CrtYd")
		)
		(fp_line
			(start 0.3048 0.9906)
			(end -0.3048 0.9906)
			(stroke
				(width 0.1)
				(type default)
			)
			(layer "B.Fab")
		)
		(fp_line
			(start 0.3048 -0.1016)
			(end 0.3048 0.9906)
			(stroke
				(width 0.1)
				(type default)
			)
			(layer "B.Fab")
		)
		(fp_line
			(start -0.3048 0.9906)
			(end -0.3048 -0.1016)
			(stroke
				(width 0.1)
				(type default)
			)
			(layer "B.Fab")
		)
		(fp_line
			(start -0.3048 -0.1016)
			(end 0.3048 -0.1016)
			(stroke
				(width 0.1)
				(type default)
			)
			(layer "B.Fab")
		)
		(pad "1" smd rect
			(at 0 0)
			(size 0.508 0.508)
			(layers "B.Cu" "B.Mask" "B.Paste")
			(net "P3V3_STBY")
		)
		(pad "2" smd rect
			(at 0 0.889)
			(size 0.508 0.508)
			(layers "B.Cu" "B.Mask" "B.Paste")
			(net "GND")
		)
		(zone
			(layer "B.Cu")
			(hatch none 0.5)
			(connect_pads
				(clearance 0)
			)
			(min_thickness 0.25)
			(keepout
				(tracks not_allowed)
				(vias allowed)
				(pads allowed)
				(copperpour not_allowed)
				(footprints allowed)
			)
			(placement
				(enabled no)
				(sheetname "")
			)
			(fill
				(thermal_gap 0.5)
				(thermal_bridge_width 0.5)
				(island_removal_mode 0)
			)
			(polygon
				(pts
					(xy 406.2222 -14.4653) (xy 406.7302 -14.4653) (xy 406.7302 -14.0843) (xy 406.2222 -14.0843)
				)
			)
		)
		(zone
			(layer "B.Cu")
			(hatch none 0.5)
			(connect_pads
				(clearance 0)
			)
			(min_thickness 0.25)
			(keepout
				(tracks allowed)
				(vias not_allowed)
				(pads allowed)
				(copperpour not_allowed)
				(footprints allowed)
			)
			(placement
				(enabled no)
				(sheetname "")
			)
			(fill
				(thermal_gap 0.5)
				(thermal_bridge_width 0.5)
				(island_removal_mode 0)
			)
			(polygon
				(pts
					(xy 406.2222 -14.0843) (xy 406.7302 -14.0843) (xy 406.7302 -14.4653) (xy 406.2222 -14.4653)
				)
			)
		)
	)
)
